# BASEBOARD_FAB2 (Tioga Pass) — schematic parts with pin connectivity, parts 4665–4665 of 4751; source: Cadence DE-HDL packaged netlist (pstxprt.dat, pstxnet.dat, pstchip.dat)

U5D1  SKX_EXT_B  IC  pkg BGA1  page 21  (pins 2035-2373 of 3647)
  DC20  UPI2_RX_DP(3)  IN  = GND
  DC22  UPI2_RX_DN(2)  IN  = GND
  DC24  VSS(271)  GROUND  = GND
  DC26  VSS(270)  GROUND  = GND
  DC28  DDR5_DQ(63)  BI  = M_F_DQ<63>
  DC30  DDR5_DQ(57)  BI  = M_F_DQ<57>
  DC32  VSS(269)  GROUND  = GND
  DC34  DDR5_DQ(55)  BI  = M_F_DQ<55>
  DC36  DDR5_DQ(49)  BI  = M_F_DQ<49>
  DC38  VSS(268)  GROUND  = GND
  DC40  DDR5_DQS_DP(13)  BI  = M_F_DQS_DP<13>
  DC42  VSS(267)  GROUND  = GND
  DC44  SVIDCLK(0)  OUT  = SVID_CLK0_CPU0
  DC46  RSVD(47)  BI  = TP_CPU0_RSVD_47
  DC48  DDR345_RCOMP(0)  BI  = A_CPU0_DEF_RCOMP0
  DC50  TEST_14  BI  = PD_CPU0_TEST14
  DC52  RSVD(46)  BI  = TP_CPU0_RSVD_46
  DC54  DDR5_MA(15)  OUT  = M_F_MA<15>
  DC56  DDR5_BA(1)  OUT  = M_F_BA<1>
  DC58  DDR5_MA(1)  OUT  = M_F_MA<1>
  DC60  DDR5_MA(7)  OUT  = M_F_MA<7>
  DC62  DDR5_ACT_N  OUT  = M_F_ACT_N
  DC64  VSS(266)  GROUND  = GND
  DC66  VSS(265)  GROUND  = GND
  DC68  VSS(264)  GROUND  = GND
  DC70  VSS(263)  GROUND  = GND
  DC72  PKGID(0)  BI  = FM_CPU0_PKGID0
  DC74  DDR5_DQ(12)  BI  = M_F_DQ<12>
  DC76  DDR5_DQ(9)  BI  = M_F_DQ<9>
  DC78  VSS(262)  GROUND  = GND
  DC80  DDR4_DQS_DN(10)  BI  = M_E_DQS_DN<10>
  DC82  DDR4_DQ(14)  BI  = M_E_DQ<14>
  DC84  VSS(261)  GROUND  = GND
  DC86  VSS(260)  GROUND  = GND
  DD3  PE1_TX_DP(2)  OUT  = P3E_CPU0_PE1_SS_TXP<2>
  DD5  PE3_TX_DN(13)  OUT  = P3E_CPU0_PE3_OCP_TXN<13>
  DD7  VCCIO(39)  POWER  = PVCCIO_CPU0
  DD9  PE1_RX_DP(4)  IN  = P3E_CPU0_PE1_SS_RXP<4>
  DD11  VSS(259)  GROUND  = GND
  DD13  PE3_RX_DN(12)  IN  = P3E_CPU0_PE3_OCP_RXN<12>
  DD15  UPI2_TX_DP(8)  OUT  = TP_CPU0_UPI2_RSVD_CV13
  DD17  UPI2_TX_DN(7)  OUT  = TP_CPU0_UPI2_RSVD_CU14
  DD19  UPI2_RX_DN(4)  IN  = GND
  DD21  UPI2_RX_DP(1)  IN  = GND
  DD23  VSS(258)  GROUND  = GND
  DD25  DDR4_DQ(58)  BI  = M_E_DQ<58>
  DD27  VSS(257)  GROUND  = GND
  DD29  DDR5_DQS_DN(7)  BI  = M_F_DQS_DN<7>
  DD31  VSS(256)  GROUND  = GND
  DD33  VSS(255)  GROUND  = GND
  DD35  DDR5_DQS_DN(6)  BI  = M_F_DQS_DN<6>
  DD37  VSS(254)  GROUND  = GND
  DD39  DDR5_DQ(38)  BI  = M_F_DQ<38>
  DD41  DDR5_DQ(32)  BI  = M_F_DQ<32>
  DD45  VCCD345(42)  POWER  = PVDDQ_DEF
  DD47  DDR345_RCOMP(1)  BI  = A_CPU0_DEF_RCOMP1
  DD49  DDR345_RCOMP(2)  BI  = A_CPU0_DEF_RCOMP2
  DD51  RSVD(45)  BI  = TP_CPU0_RSVD_45
  DD53  DDR5_MA(13)  OUT  = M_F_MA<13>
  DD55  DDR5_MA(10)  OUT  = M_F_MA<10>
  DD57  DDR5_MA(2)  OUT  = M_F_MA<2>
  DD59  DDR5_MA(8)  OUT  = M_F_MA<8>
  DD61  DDR5_ALERT_N  IN  = M_F_ALERT_N
  DD63  DDR5_CKE(1)  OUT  = M_F_CKE<1>
  DD65  DDR3_ECC(3)  BI  = M_D_ECC<3>
  DD67  DDR3_DQS_DP(8)  BI  = M_D_DQS_DP<8>
  DD69  DDR3_ECC(5)  BI  = M_D_ECC<5>
  DD71  VSS(253)  GROUND  = GND
  DD73  VSS(252)  GROUND  = GND
  DD75  VSS(251)  GROUND  = GND
  DD77  DDR5_DQS_DN(1)  BI  = M_F_DQS_DN<1>
  DD79  DDR4_DQS_DP(10)  BI  = M_E_DQS_DP<10>
  DD81  VSS(250)  GROUND  = GND
  DD83  VSS(249)  GROUND  = GND
  DD85  DDR3_DQ(12)  BI  = M_D_DQ<12>
  DE2  PE1_TX_DN(2)  OUT  = P3E_CPU0_PE1_SS_TXN<2>
  DE4  PE1_TX_DN(3)  OUT  = P3E_CPU0_PE1_SS_TXN<3>
  DE6  VSS(248)  GROUND  = GND
  DE8  VSS(247)  GROUND  = GND
  DE10  PE1_RX_DN(4)  IN  = P3E_CPU0_PE1_SS_RXN<4>
  DE12  PE3_RX_DP(10)  IN  = P3E_CPU0_PE3_OCP_RXP<10>
  DE14  VCCIO(13)  POWER  = PVCCIO_CPU0
  DE16  UPI2_TX_DP(7)  OUT  = TP_CPU0_UPI2_RSVD_CR14
  DE18  VSS(246)  GROUND  = GND
  DE20  VSS(245)  GROUND  = GND
  DE22  UPI2_RX_DN(1)  IN  = GND
  DE24  VSS(244)  GROUND  = GND
  DE26  DDR4_DQS_DP(16)  BI  = M_E_DQS_DP<16>
  DE28  VSS(243)  GROUND  = GND
  DE30  VSS(242)  GROUND  = GND
  DE32  DDR5_DQS_DP(14)  BI  = M_F_DQS_DP<14>
  DE34  VSS(241)  GROUND  = GND
  DE36  VSS(240)  GROUND  = GND
  DE38  DDR5_DQ(34)  BI  = M_F_DQ<34>
  DE40  DDR5_DQS_DN(13)  BI  = M_F_DQS_DN<13>
  DE42  DDR5_DQ(37)  BI  = M_F_DQ<37>
  DE44  SVIDALERT_N(0)  IN  = SVID_ALERT0_CPU0_N
  DE46  DDR5_MA(17)  OUT  = M_F_MA<17>
  DE48  VSS(1193)  GROUND  = GND
  DE50  VSS(1194)  GROUND  = GND
  DE52  VSS(1195)  GROUND  = GND
  DE54  VSS(1196)  GROUND  = GND
  DE56  VSS(1197)  GROUND  = GND
  DE58  VSS(1198)  GROUND  = GND
  DE60  VSS(1199)  GROUND  = GND
  DE62  VSS(1200)  GROUND  = GND
  DE64  VSS(239)  GROUND  = GND
  DE66  DDR3_ECC(7)  BI  = M_D_ECC<7>
  DE68  DDR3_ECC(1)  BI  = M_D_ECC<1>
  DE70  VSS(238)  GROUND  = GND
  DE72  VSS(237)  GROUND  = GND
  DE74  DDR5_DQ(8)  BI  = M_F_DQ<8>
  DE76  DDR5_DQS_DP(1)  BI  = M_F_DQS_DP<1>
  DE78  VSS(236)  GROUND  = GND
  DE80  DDR4_DQ(10)  BI  = M_E_DQ<10>
  DE82  DDR4_DQ(15)  BI  = M_E_DQ<15>
  DE84  DDR3_DQ(13)  BI  = M_D_DQ<13>
  DF3  PE1_TX_DP(4)  OUT  = P3E_CPU0_PE1_SS_TXP<4>
  DF5  VSS(235)  GROUND  = GND
  DF7  VSS(234)  GROUND  = GND
  DF9  PE1_RX_DP(5)  IN  = P3E_CPU0_PE1_SS_RXP<5>
  DF11  PE3_RX_DP(11)  IN  = P3E_CPU0_PE3_OCP_RXP<11>
  DF13  VCCIO(41)  POWER  = PVCCIO_CPU0
  DF15  UPI2_TX_DN(8)  OUT  = TP_CPU0_UPI2_RSVD_CW14
  DF17  UPI2_TX_DP(6)  OUT  = TP_CPU0_UPI2_RSVD_CK13
  DF19  VSS(232)  GROUND  = GND
  DF21  VCCIO(48)  POWER  = PVCCIO_CPU0
  DF23  UPI2_RX_DN(0)  IN  = GND
  DF25  DDR4_DQ(62)  BI  = M_E_DQ<62>
  DF27  DDR4_DQ(56)  BI  = M_E_DQ<56>
  DF29  VSS(231)  GROUND  = GND
  DF31  DDR5_DQ(46)  BI  = M_F_DQ<46>
  DF33  DDR5_DQ(40)  BI  = M_F_DQ<40>
  DF35  VSS(230)  GROUND  = GND
  DF37  VSS(229)  GROUND  = GND
  DF39  VSS(228)  GROUND  = GND
  DF41  VSS(227)  GROUND  = GND
  DF45  DDR5_CID(2)  OUT  = M_F_C<2>
  DF47  DDR5_ODT(3)  OUT  = M_F_ODT<3>
  DF49  DDR5_CS_N(1)  OUT  = M_F_CS_N<1>
  DF51  DDR5_CS_N(4)  OUT  = M_F_CS_N<4>
  DF53  DDR5_MA(0)  OUT  = M_F_MA<0>
  DF55  DDR5_CLK_DN(1)  OUT  = M_F_CLK_DN<1>
  DF57  DDR5_CLK_DN(3)  OUT  = M_F_CLK_DN<3>
  DF59  DDR5_MA(5)  OUT  = M_F_MA<5>
  DF61  DDR5_BG(1)  OUT  = M_F_BG<1>
  DF63  DDR5_CKE(3)  OUT  = M_F_CKE<3>
  DF65  VSS(226)  GROUND  = GND
  DF67  DDR3_DQS_DN(8)  BI  = M_D_DQS_DN<8>
  DF69  VSS(225)  GROUND  = GND
  DF71  DDR5_DQ(20)  BI  = M_F_DQ<20>
  DF73  VSS(224)  GROUND  = GND
  DF75  DDR5_DQS_DN(10)  BI  = M_F_DQS_DN<10>
  DF77  DDR5_DQ(14)  BI  = M_F_DQ<14>
  DF79  VSS(223)  GROUND  = GND
  DF81  DDR4_DQ(11)  BI  = M_E_DQ<11>
  DF83  VSS(222)  GROUND  = GND
  DF85  VSS(221)  GROUND  = GND
  DG2  VSS(220)  GROUND  = GND
  DG4  PE1_TX_DN(4)  OUT  = P3E_CPU0_PE1_SS_TXN<4>
  DG6  PE3_TX_DP(12)  OUT  = P3E_CPU0_PE3_OCP_TXP<12>
  DG8  VCCIO(54)  POWER  = PVCCIO_CPU0
  DG10  PE3_RX_DN(11)  IN  = P3E_CPU0_PE3_OCP_RXN<11>
  DG12  PE3_RX_DN(10)  IN  = P3E_CPU0_PE3_OCP_RXN<10>
  DG14  VSS(218)  GROUND  = GND
  DG16  VSS(217)  GROUND  = GND
  DG18  UPI2_TX_DN(6)  OUT  = TP_CPU0_UPI2_RSVD_CM13
  DG20  UPI2_TX_DN(3)  OUT  = TP_CPU0_UPI2_RSVD_CH11
  DG22  UPI2_RX_DP(0)  IN  = GND
  DG24  VSS(216)  GROUND  = GND
  DG26  DDR4_DQS_DN(16)  BI  = M_E_DQS_DN<16>
  DG28  DDR4_DQ(60)  BI  = M_E_DQ<60>
  DG30  DDR5_DQ(42)  BI  = M_F_DQ<42>
  DG32  DDR5_DQS_DN(14)  BI  = M_F_DQS_DN<14>
  DG34  DDR5_DQ(44)  BI  = M_F_DQ<44>
  DG36  RSVD(44)  BI  = TP_CPU0_RSVD_44
  DG38  DDR5_DQ(35)  BI  = M_F_DQ<35>
  DG40  DDR5_DQS_DN(4)  BI  = M_F_DQS_DN<4>
  DG42  DDR5_DQ(33)  BI  = M_F_DQ<33>
  DG44  SVIDCLK(1)  OUT  = SVID_CLK1_CPU0
  DG46  DDR5_CS_N(3)  OUT  = M_F_CS_N<3>
  DG48  DDR5_ODT(1)  OUT  = M_F_ODT<1>
  DG50  DDR5_ODT(0)  OUT  = M_F_ODT<0>
  DG52  DDR5_MA(16)  OUT  = M_F_MA<16>
  DG54  DDR5_CLK_DP(1)  OUT  = M_F_CLK_DP<1>
  DG56  DDR5_CLK_DP(3)  OUT  = M_F_CLK_DP<3>
  DG58  DDR5_MA(3)  OUT  = M_F_MA<3>
  DG60  DDR5_MA(12)  OUT  = M_F_MA<12>
  DG62  DDR5_CKE(0)  OUT  = M_F_CKE<0>
  DG64  RSVD(43)  BI  = TP_CPU0_RSVD_43
  DG66  VSS(215)  GROUND  = GND
  DG68  VSS(214)  GROUND  = GND
  DG70  DDR5_DQ(16)  BI  = M_F_DQ<16>
  DG72  DDR5_DQ(21)  BI  = M_F_DQ<21>
  DG74  DDR5_DQS_DP(10)  BI  = M_F_DQS_DP<10>
  DG76  VSS(213)  GROUND  = GND
  DG78  VSS(212)  GROUND  = GND
  DG80  VSS(211)  GROUND  = GND
  DG82  VSS(210)  GROUND  = GND
  DG84  DDR3_DQ(8)  BI  = M_D_DQ<8>
  DH3  PE1_TX_DP(5)  OUT  = P3E_CPU0_PE1_SS_TXP<5>
  DH5  PE3_TX_DP(11)  OUT  = P3E_CPU0_PE3_OCP_TXP<11>
  DH7  VCCIO(55)  POWER  = PVCCIO_CPU0
  DH9  PE1_RX_DN(5)  IN  = P3E_CPU0_PE1_SS_RXN<5>
  DH11  PE3_RX_DP(9)  IN  = P3E_CPU0_PE3_OCP_RXP<9>
  DH13  VSS(209)  GROUND  = GND
  DH15  VSS(208)  GROUND  = GND
  DH17  UPI2_TX_DP(5)  OUT  = TP_CPU0_UPI2_RSVD_CH13
  DH19  UPI2_TX_DN(4)  OUT  = TP_CPU0_UPI2_RSVD_CF13
  DH21  VSS(102)  GROUND  = GND
  DH23  VSS(207)  GROUND  = GND
  DH25  VSS(206)  GROUND  = GND
  DH27  VSS(205)  GROUND  = GND
  DH29  VSS(204)  GROUND  = GND
  DH31  VSS(203)  GROUND  = GND
  DH33  VSS(202)  GROUND  = GND
  DH35  VSS(201)  GROUND  = GND
  DH37  VSS(200)  GROUND  = GND
  DH39  DDR5_DQ(39)  BI  = M_F_DQ<39>
  DH41  VSS(199)  GROUND  = GND
  DH45  VCCD345(41)  POWER  = PVDDQ_DEF
  DH47  VCCD345(40)  POWER  = PVDDQ_DEF
  DH49  VCCD345(39)  POWER  = PVDDQ_DEF
  DH51  VCCD345(38)  POWER  = PVDDQ_DEF
  DH53  VCCD345(37)  POWER  = PVDDQ_DEF
  DH55  VCCD345(36)  POWER  = PVDDQ_DEF
  DH57  VCCD345(35)  POWER  = PVDDQ_DEF
  DH59  VCCD345(34)  POWER  = PVDDQ_DEF
  DH61  VCCD345(33)  POWER  = PVDDQ_DEF
  DH63  VCCD345(32)  POWER  = PVDDQ_DEF
  DH65  RSVD(42)  BI  = TP_CPU0_RSVD_42
  DH67  VSS(198)  GROUND  = GND
  DH69  DDR5_DQS_DP(11)  BI  = M_F_DQS_DP<11>
  DH71  VSS(197)  GROUND  = GND
  DH73  VSS(196)  GROUND  = GND
  DH75  DDR5_DQ(10)  BI  = M_F_DQ<10>
  DH77  DDR5_DQ(15)  BI  = M_F_DQ<15>
  DH79  VSS(195)  GROUND  = GND
  DH81  VSS(194)  GROUND  = GND
  DH83  VSS(193)  GROUND  = GND
  DH85  DDR3_DQ(9)  BI  = M_D_DQ<9>
  DJ2  VSS(192)  GROUND  = GND
  DJ4  PE3_TX_DN(11)  OUT  = P3E_CPU0_PE3_OCP_TXN<11>
  DJ6  PE3_TX_DN(12)  OUT  = P3E_CPU0_PE3_OCP_TXN<12>
  DJ8  PE1_RX_DP(6)  IN  = P3E_CPU0_PE1_SS_RXP<6>
  DJ10  VSS(191)  GROUND  = GND
  DJ12  PE3_RX_DN(9)  IN  = P3E_CPU0_PE3_OCP_RXN<9>
  DJ14  PE3_RX_DP(7)  IN  = P3E_CPU0_PE3_OCP_RXP<7>
  DJ16  VCCIO(60)  POWER  = PVCCIO_CPU0
  DJ18  UPI2_TX_DP(4)  OUT  = TP_CPU0_UPI2_RSVD_CG12
  DJ20  UPI2_TX_DP(3)  OUT  = TP_CPU0_UPI2_RSVD_CF11
  DJ22  VSS(189)  GROUND  = GND
  DJ24  DDR4_DQ(59)  BI  = M_E_DQ<59>
  DJ26  DDR4_DQS_DP(7)  BI  = M_E_DQS_DP<7>
  DJ28  DDR4_DQ(61)  BI  = M_E_DQ<61>
  DJ30  DDR5_DQ(43)  BI  = M_F_DQ<43>
  DJ32  DDR5_DQS_DP(5)  BI  = M_F_DQS_DP<5>
  DJ34  DDR5_DQ(45)  BI  = M_F_DQ<45>
  DJ36  RSVD(41)  BI  = TP_CPU0_RSVD_41
  DJ38  VSS(188)  GROUND  = GND
  DJ40  DDR5_DQS_DP(4)  BI  = M_F_DQS_DP<4>
  DJ42  VSS(187)  GROUND  = GND
  DJ44  SVIDDATA(1)  BI  = SVID_DIO1_CPU0
  DJ46  DDR5_CS_N(2)  OUT  = M_F_CS_N<2>
  DJ48  DDR5_CS_N(5)  OUT  = M_F_CS_N<5>
  DJ50  DDR5_MA(14)  OUT  = M_F_MA<14>
  DJ52  DDR5_BA(0)  OUT  = M_F_BA<0>
  DJ54  DDR5_CLK_DP(0)  OUT  = M_F_CLK_DP<0>
  DJ56  DDR5_CLK_DP(2)  OUT  = M_F_CLK_DP<2>
  DJ58  DDR5_MA(4)  OUT  = M_F_MA<4>
  DJ60  DDR4_MA(8)  OUT  = M_E_MA<8>
  DJ62  DDR4_BG(0)  OUT  = M_E_BG<0>
  DJ64  VCCD345(31)  POWER  = PVDDQ_DEF
  DJ66  RSVD(40)  BI  = TP_CPU0_RSVD_40
  DJ68  VSS(186)  GROUND  = GND
  DJ70  DDR5_DQS_DN(11)  BI  = M_F_DQS_DN<11>
  DJ72  DDR5_DQ(17)  BI  = M_F_DQ<17>
  DJ74  VSS(185)  GROUND  = GND
  DJ76  DDR5_DQ(11)  BI  = M_F_DQ<11>
  DJ78  VSS(184)  GROUND  = GND
  DJ80  DDR3_DQ(21)  BI  = M_D_DQ<21>
  DJ82  VSS(183)  GROUND  = GND
  DJ84  VSS(182)  GROUND  = GND
  DK3  PE1_TX_DN(5)  OUT  = P3E_CPU0_PE1_SS_TXN<5>
  DK5  PE3_TX_DP(10)  OUT  = P3E_CPU0_PE3_OCP_TXP<10>
  DK7  VSS(181)  GROUND  = GND
  DK9  PE1_RX_DN(6)  IN  = P3E_CPU0_PE1_SS_RXN<6>
  DK11  PE1_RX_DP(8)  IN  = P3E_CPU0_PE1_PCH_RXP<8>
  DK13  PE3_RX_DP(8)  IN  = P3E_CPU0_PE3_OCP_RXP<8>
  DK15  RSVD(39)  BI  = TP_CPU0_RSVD_39
  DK17  UPI2_TX_DN(5)  OUT  = TP_CPU0_UPI2_RSVD_CJ14
  DK19  UPI2_TX_DP(2)  OUT  = TP_CPU0_UPI2_RSVD_CD11
  DK21  VCCIO(8)  POWER  = PVCCIO_CPU0
  DK23  VSS(180)  GROUND  = GND
  DK25  DDR4_DQ(63)  BI  = M_E_DQ<63>
  DK27  DDR4_DQ(57)  BI  = M_E_DQ<57>
  DK29  VSS(179)  GROUND  = GND
  DK31  DDR5_DQ(47)  BI  = M_F_DQ<47>
  DK33  DDR5_DQ(41)  BI  = M_F_DQ<41>
  DK35  VSS(178)  GROUND  = GND
  DK37  RSVD(38)  BI  = TP_CPU0_RSVD_38
  DK39  VSS(177)  GROUND  = GND
  DK41  VSS(176)  GROUND  = GND
  DK45  DDR5_CS_N(7)  OUT  = M_F_CS_N<7>
  DK47  DDR4_CS_N(3)  OUT  = M_E_CS_N<3>
  DK49  DDR5_ODT(2)  OUT  = M_F_ODT<2>
  DK51  DDR5_CS_N(0)  OUT  = M_F_CS_N<0>
  DK53  DDR5_PAR  OUT  = M_F_PAR
  DK55  DDR5_CLK_DN(0)  OUT  = M_F_CLK_DN<0>
  DK57  DDR5_CLK_DN(2)  OUT  = M_F_CLK_DN<2>
  DK59  DDR5_MA(6)  OUT  = M_F_MA<6>
  DK61  DDR4_MA(7)  OUT  = M_E_MA<7>
  DK63  DDR5_CKE(2)  OUT  = M_F_CKE<2>
  DK65  RSVD(37)  BI  = TP_CPU0_RSVD_37
  DK67  RSVD(36)  BI  = TP_CPU0_RSVD_36
  DK69  DDR5_DQ(22)  BI  = M_F_DQ<22>
  DK71  DDR5_DQS_DP(2)  BI  = M_F_DQS_DP<2>
  DK73  VSS(175)  GROUND  = GND
  DK75  VSS(174)  GROUND  = GND
  DK77  VSS(173)  GROUND  = GND
  DK79  DDR3_DQ(20)  BI  = M_D_DQ<20>
  DK81  DDR3_DQ(17)  BI  = M_D_DQ<17>
  DK83  VSS(172)  GROUND  = GND
  DK85  VSS(171)  GROUND  = GND
  DL2  PE1_TX_DP(6)  OUT  = P3E_CPU0_PE1_SS_TXP<6>
  DL4  VSS(168)  GROUND  = GND
  DL6  PE3_TX_DN(10)  OUT  = P3E_CPU0_PE3_OCP_TXN<10>
  DL8  VSS(1201)  GROUND  = GND
  DL10  PE1_RX_DP(7)  IN  = P3E_CPU0_PE1_SS_RXP<7>
  DL12  PE3_RX_DN(8)  IN  = P3E_CPU0_PE3_OCP_RXN<8>
  DL14  PE3_RX_DN(7)  IN  = P3E_CPU0_PE3_OCP_RXN<7>
  DL16  VSS(170)  GROUND  = GND
  DL18  VSS(169)  GROUND  = GND
  DL20  UPI2_TX_DN(2)  OUT  = TP_CPU0_UPI2_RSVD_CE12
  DL22  VSS(167)  GROUND  = GND
  DL24  VSS(166)  GROUND  = GND
  DL26  DDR4_DQS_DN(7)  BI  = M_E_DQS_DN<7>
  DL28  VSS(165)  GROUND  = GND
  DL30  VSS(164)  GROUND  = GND
